# T6G (Grand Teton) — schematic netlist excerpt (pin names and nets, part order shuffled) for the footprints in the layout excerpt that follows; sources: Cadence DE-HDL packaged netlist, KiCad conversion of 04192023_DAF0TMB3IC0_F0TG_MB_C_brd_V02_OCP.brd

C2617  Q_CAP  22UF 4V 20% X6S  pkg C0402  page 70 : A = PVDD11_S3_P0 ; B = GND
C568  Q_CAP  22UF 4V 20% X6S  pkg C0402  page 279 : A = P0V9_CPU0_RT0_2A ; B = GND

(kicad_pcb
	(version 20260206)
	(generator "pcbnew")
	(generator_version "10.0")
	(general
		(thickness 1.6)
		(legacy_teardrops no)
	)
	(paper "A4")
	(title_block
		(title "04192023_DAF0TMB3IC0_F0TG_MB_C_brd_V02_OCP.brd")
		(comment 1 "Grand Teton / footprints 5778-5779 of 8354")
	)
	(layers
		(0 "F.Cu" signal "TOP")
		(4 "In1.Cu" signal "GND")
		(6 "In2.Cu" signal "IN1")
		(8 "In3.Cu" signal "GND1")
		(10 "In4.Cu" signal "IN2")
		(12 "In5.Cu" signal "GND2")
		(14 "In6.Cu" signal "IN3")
		(16 "In7.Cu" signal "GND3")
		(18 "In8.Cu" signal "VCC")
		(20 "In9.Cu" signal "VCC1")
		(22 "In10.Cu" signal "GND4")
		(24 "In11.Cu" signal "IN4")
		(26 "In12.Cu" signal "GND5")
		(28 "In13.Cu" signal "IN5")
		(30 "In14.Cu" signal "GND6")
		(32 "In15.Cu" signal "IN6")
		(34 "In16.Cu" signal "GND7")
		(2 "B.Cu" signal "BOTTOM")
		(9 "F.Adhes" user "F.Adhesive")
		(11 "B.Adhes" user "B.Adhesive")
		(13 "F.Paste" user "Package Geometry/Pastemask Top")
		(15 "B.Paste" user "Package Geometry/Pastemask Bottom")
		(5 "F.SilkS" user "Ref Des/Silkscreen Top")
		(7 "B.SilkS" user "Ref Des/Silkscreen Bottom")
		(1 "F.Mask" user "Board Geometry/Soldermask Top")
		(3 "B.Mask" user "Board Geometry/Soldermask Bottom")
		(17 "Dwgs.User" user "User.Drawings")
		(19 "Cmts.User" user "User.Comments")
		(21 "Eco1.User" user "User.Eco1")
		(23 "Eco2.User" user "User.Eco2")
		(25 "Edge.Cuts" user "Board Geometry/Outline")
		(27 "Margin" user)
		(31 "F.CrtYd" user "Package Geometry/Place Bound Top")
		(29 "B.CrtYd" user "Package Geometry/Place Bound Bottom")
		(35 "F.Fab" user "Ref Des/Assembly Top")
		(33 "B.Fab" user "Ref Des/Assembly Bottom")
	)
	(footprint ""
		(layer "B.Cu")
		(at 358.467152 -261.747762 90)
		(property "Reference" "C2617"
			(at 0 0 90)
			(layer "B.SilkS")
			(hide yes)
			(effects
				(font
					(size 1.27 1.27)
				)
				(justify mirror)
			)
		)
		(property "Value" ""
			(at 0 0 90)
			(layer "B.Fab")
			(effects
				(font
					(size 1.27 1.27)
				)
				(justify mirror)
			)
		)
		(duplicate_pad_numbers_are_jumpers no)
		(fp_line
			(start 0.7874 -0.4064)
			(end -0.7874 -0.4064)
			(stroke
				(width 0.1524)
				(type default)
			)
			(layer "B.SilkS")
		)
		(fp_line
			(start -0.7874 -0.4064)
			(end -0.7874 0.4064)
			(stroke
				(width 0.1524)
				(type default)
			)
			(layer "B.SilkS")
		)
		(fp_line
			(start 0.7874 0.4064)
			(end 0.7874 -0.4064)
			(stroke
				(width 0.1524)
				(type default)
			)
			(layer "B.SilkS")
		)
		(fp_line
			(start -0.7874 0.4064)
			(end 0.7874 0.4064)
			(stroke
				(width 0.1524)
				(type default)
			)
			(layer "B.SilkS")
		)
		(fp_line
			(start 0.67945 -0.305054)
			(end 0.12065 -0.305054)
			(stroke
				(width 0.1)
				(type default)
			)
			(layer "B.Fab")
		)
		(fp_line
			(start 0.12065 -0.305054)
			(end 0.12065 -0.2794)
			(stroke
				(width 0.1)
				(type default)
			)
			(layer "B.Fab")
		)
		(fp_line
			(start -0.12065 -0.3048)
			(end -0.67945 -0.3048)
			(stroke
				(width 0.1)
				(type default)
			)
			(layer "B.Fab")
		)
		(fp_line
			(start -0.67945 -0.3048)
			(end -0.67945 0.3048)
			(stroke
				(width 0.1)
				(type default)
			)
			(layer "B.Fab")
		)
		(fp_line
			(start 0.12065 -0.2794)
			(end -0.12065 -0.2794)
			(stroke
				(width 0.1)
				(type default)
			)
			(layer "B.Fab")
		)
		(fp_line
			(start -0.12065 -0.2794)
			(end -0.12065 -0.3048)
			(stroke
				(width 0.1)
				(type default)
			)
			(layer "B.Fab")
		)
		(fp_line
			(start 0.12065 0.2794)
			(end 0.12065 0.3048)
			(stroke
				(width 0.1)
				(type default)
			)
			(layer "B.Fab")
		)
		(fp_line
			(start -0.120396 0.2794)
			(end 0.12065 0.2794)
			(stroke
				(width 0.1)
				(type default)
			)
			(layer "B.Fab")
		)
		(fp_line
			(start 0.67945 0.3048)
			(end 0.67945 -0.305054)
			(stroke
				(width 0.1)
				(type default)
			)
			(layer "B.Fab")
		)
		(fp_line
			(start 0.12065 0.3048)
			(end 0.67945 0.3048)
			(stroke
				(width 0.1)
				(type default)
			)
			(layer "B.Fab")
		)
		(fp_line
			(start -0.120396 0.3048)
			(end -0.120396 0.2794)
			(stroke
				(width 0.1)
				(type default)
			)
			(layer "B.Fab")
		)
		(fp_line
			(start -0.67945 0.3048)
			(end -0.120396 0.3048)
			(stroke
				(width 0.1)
				(type default)
			)
			(layer "B.Fab")
		)
		(pad "1" smd circle
			(at 0.40005 0 270)
			(size 0 0)
			(layers "B.Cu" "B.Mask" "B.Paste")
			(net "PVDD11_S3_P0")
		)
		(pad "2" smd circle
			(at -0.40005 0 270)
			(size 0 0)
			(layers "B.Cu" "B.Mask" "B.Paste")
			(net "GND")
		)
	)
	(footprint ""
		(layer "B.Cu")
		(at 308.191154 -398.942052 90)
		(property "Reference" "C568"
			(at 0 0 90)
			(layer "B.SilkS")
			(hide yes)
			(effects
				(font
					(size 1.27 1.27)
				)
				(justify mirror)
			)
		)
		(property "Value" ""
			(at 0 0 90)
			(layer "B.Fab")
			(effects
				(font
					(size 1.27 1.27)
				)
				(justify mirror)
			)
		)
		(duplicate_pad_numbers_are_jumpers no)
		(fp_line
			(start 0.7874 -0.4064)
			(end -0.7874 -0.4064)
			(stroke
				(width 0.1524)
				(type default)
			)
			(layer "B.SilkS")
		)
		(fp_line
			(start -0.7874 -0.4064)
			(end -0.7874 0.4064)
			(stroke
				(width 0.1524)
				(type default)
			)
			(layer "B.SilkS")
		)
		(fp_line
			(start 0.7874 0.4064)
			(end 0.7874 -0.4064)
			(stroke
				(width 0.1524)
				(type default)
			)
			(layer "B.SilkS")
		)
		(fp_line
			(start -0.7874 0.4064)
			(end 0.7874 0.4064)
			(stroke
				(width 0.1524)
				(type default)
			)
			(layer "B.SilkS")
		)
		(fp_line
			(start 0.67945 -0.305054)
			(end 0.12065 -0.305054)
			(stroke
				(width 0.1)
				(type default)
			)
			(layer "B.Fab")
		)
		(fp_line
			(start 0.12065 -0.305054)
			(end 0.12065 -0.2794)
			(stroke
				(width 0.1)
				(type default)
			)
			(layer "B.Fab")
		)
		(fp_line
			(start -0.12065 -0.3048)
			(end -0.67945 -0.3048)
			(stroke
				(width 0.1)
				(type default)
			)
			(layer "B.Fab")
		)
		(fp_line
			(start -0.67945 -0.3048)
			(end -0.67945 0.3048)
			(stroke
				(width 0.1)
				(type default)
			)
			(layer "B.Fab")
		)
		(fp_line
			(start 0.12065 -0.2794)
			(end -0.12065 -0.2794)
			(stroke
				(width 0.1)
				(type default)
			)
			(layer "B.Fab")
		)
		(fp_line
			(start -0.12065 -0.2794)
			(end -0.12065 -0.3048)
			(stroke
				(width 0.1)
				(type default)
			)
			(layer "B.Fab")
		)
		(fp_line
			(start 0.12065 0.2794)
			(end 0.12065 0.3048)
			(stroke
				(width 0.1)
				(type default)
			)
			(layer "B.Fab")
		)
		(fp_line
			(start -0.120396 0.2794)
			(end 0.12065 0.2794)
			(stroke
				(width 0.1)
				(type default)
			)
			(layer "B.Fab")
		)
		(fp_line
			(start 0.67945 0.3048)
			(end 0.67945 -0.305054)
			(stroke
				(width 0.1)
				(type default)
			)
			(layer "B.Fab")
		)
		(fp_line
			(start 0.12065 0.3048)
			(end 0.67945 0.3048)
			(stroke
				(width 0.1)
				(type default)
			)
			(layer "B.Fab")
		)
		(fp_line
			(start -0.120396 0.3048)
			(end -0.120396 0.2794)
			(stroke
				(width 0.1)
				(type default)
			)
			(layer "B.Fab")
		)
		(fp_line
			(start -0.67945 0.3048)
			(end -0.120396 0.3048)
			(stroke
				(width 0.1)
				(type default)
			)
			(layer "B.Fab")
		)
		(pad "1" smd circle
			(at 0.40005 0 270)
			(size 0 0)
			(layers "B.Cu" "B.Mask" "B.Paste")
			(net "P0V9_CPU0_RT0_2A")
		)
		(pad "2" smd circle
			(at -0.40005 0 270)
			(size 0 0)
			(layers "B.Cu" "B.Mask" "B.Paste")
			(net "GND")
		)
	)
)
